# T6G (Grand Teton) — schematic netlist excerpt (pin names and nets, part order shuffled) for the footprints in the layout excerpt that follows; sources: Cadence DE-HDL packaged netlist, KiCad conversion of 04192023_DAF0TMB3IC0_F0TG_MB_C_brd_V02_OCP.brd

R1125  Q_RES  0 5% CHIP  pkg 0201LF  page 310 : A = NCF_CPU0_P3_GND ; B = GND
C602  Q_CAP  0.1UF 10V 10% X7S  pkg C0201  page 290 : A = P1V8_CPU0_RT1_1A ; B = GND
C2208  Q_CAP  22UF 4V 20% X6S  pkg C0402  page 69 : A = PVDDCR_CPU1_P0 ; B = GND

(kicad_pcb
	(version 20260206)
	(generator "pcbnew")
	(generator_version "10.0")
	(general
		(thickness 1.6)
		(legacy_teardrops no)
	)
	(paper "A4")
	(title_block
		(title "04192023_DAF0TMB3IC0_F0TG_MB_C_brd_V02_OCP.brd")
		(comment 1 "Grand Teton / footprints 6696-6698 of 8354")
	)
	(layers
		(0 "F.Cu" signal "TOP")
		(4 "In1.Cu" signal "GND")
		(6 "In2.Cu" signal "IN1")
		(8 "In3.Cu" signal "GND1")
		(10 "In4.Cu" signal "IN2")
		(12 "In5.Cu" signal "GND2")
		(14 "In6.Cu" signal "IN3")
		(16 "In7.Cu" signal "GND3")
		(18 "In8.Cu" signal "VCC")
		(20 "In9.Cu" signal "VCC1")
		(22 "In10.Cu" signal "GND4")
		(24 "In11.Cu" signal "IN4")
		(26 "In12.Cu" signal "GND5")
		(28 "In13.Cu" signal "IN5")
		(30 "In14.Cu" signal "GND6")
		(32 "In15.Cu" signal "IN6")
		(34 "In16.Cu" signal "GND7")
		(2 "B.Cu" signal "BOTTOM")
		(9 "F.Adhes" user "F.Adhesive")
		(11 "B.Adhes" user "B.Adhesive")
		(13 "F.Paste" user "Package Geometry/Pastemask Top")
		(15 "B.Paste" user "Package Geometry/Pastemask Bottom")
		(5 "F.SilkS" user "Ref Des/Silkscreen Top")
		(7 "B.SilkS" user "Ref Des/Silkscreen Bottom")
		(1 "F.Mask" user "Board Geometry/Soldermask Top")
		(3 "B.Mask" user "Board Geometry/Soldermask Bottom")
		(17 "Dwgs.User" user "User.Drawings")
		(19 "Cmts.User" user "User.Comments")
		(21 "Eco1.User" user "User.Eco1")
		(23 "Eco2.User" user "User.Eco2")
		(25 "Edge.Cuts" user "Board Geometry/Outline")
		(27 "Margin" user)
		(31 "F.CrtYd" user "Package Geometry/Place Bound Top")
		(29 "B.CrtYd" user "Package Geometry/Place Bound Bottom")
		(35 "F.Fab" user "Ref Des/Assembly Top")
		(33 "B.Fab" user "Ref Des/Assembly Bottom")
	)
	(footprint ""
		(layer "B.Cu")
		(at 366.598454 -269.30731 180)
		(property "Reference" "C2208"
			(at 0 0 0)
			(layer "B.SilkS")
			(hide yes)
			(effects
				(font
					(size 1.27 1.27)
				)
				(justify mirror)
			)
		)
		(property "Value" ""
			(at 0 0 0)
			(layer "B.Fab")
			(effects
				(font
					(size 1.27 1.27)
				)
				(justify mirror)
			)
		)
		(duplicate_pad_numbers_are_jumpers no)
		(fp_line
			(start 0.7874 0.4064)
			(end 0.7874 -0.4064)
			(stroke
				(width 0.1524)
				(type default)
			)
			(layer "B.SilkS")
		)
		(fp_line
			(start 0.7874 -0.4064)
			(end -0.7874 -0.4064)
			(stroke
				(width 0.1524)
				(type default)
			)
			(layer "B.SilkS")
		)
		(fp_line
			(start -0.7874 0.4064)
			(end 0.7874 0.4064)
			(stroke
				(width 0.1524)
				(type default)
			)
			(layer "B.SilkS")
		)
		(fp_line
			(start -0.7874 -0.4064)
			(end -0.7874 0.4064)
			(stroke
				(width 0.1524)
				(type default)
			)
			(layer "B.SilkS")
		)
		(fp_line
			(start 0.67945 0.3048)
			(end 0.67945 -0.305054)
			(stroke
				(width 0.1)
				(type default)
			)
			(layer "B.Fab")
		)
		(fp_line
			(start 0.67945 -0.305054)
			(end 0.12065 -0.305054)
			(stroke
				(width 0.1)
				(type default)
			)
			(layer "B.Fab")
		)
		(fp_line
			(start 0.12065 0.3048)
			(end 0.67945 0.3048)
			(stroke
				(width 0.1)
				(type default)
			)
			(layer "B.Fab")
		)
		(fp_line
			(start 0.12065 0.2794)
			(end 0.12065 0.3048)
			(stroke
				(width 0.1)
				(type default)
			)
			(layer "B.Fab")
		)
		(fp_line
			(start 0.12065 -0.2794)
			(end -0.12065 -0.2794)
			(stroke
				(width 0.1)
				(type default)
			)
			(layer "B.Fab")
		)
		(fp_line
			(start 0.12065 -0.305054)
			(end 0.12065 -0.2794)
			(stroke
				(width 0.1)
				(type default)
			)
			(layer "B.Fab")
		)
		(fp_line
			(start -0.120396 0.3048)
			(end -0.120396 0.2794)
			(stroke
				(width 0.1)
				(type default)
			)
			(layer "B.Fab")
		)
		(fp_line
			(start -0.120396 0.2794)
			(end 0.12065 0.2794)
			(stroke
				(width 0.1)
				(type default)
			)
			(layer "B.Fab")
		)
		(fp_line
			(start -0.12065 -0.2794)
			(end -0.12065 -0.3048)
			(stroke
				(width 0.1)
				(type default)
			)
			(layer "B.Fab")
		)
		(fp_line
			(start -0.12065 -0.3048)
			(end -0.67945 -0.3048)
			(stroke
				(width 0.1)
				(type default)
			)
			(layer "B.Fab")
		)
		(fp_line
			(start -0.67945 0.3048)
			(end -0.120396 0.3048)
			(stroke
				(width 0.1)
				(type default)
			)
			(layer "B.Fab")
		)
		(fp_line
			(start -0.67945 -0.3048)
			(end -0.67945 0.3048)
			(stroke
				(width 0.1)
				(type default)
			)
			(layer "B.Fab")
		)
		(pad "1" smd circle
			(at 0.40005 0)
			(size 0 0)
			(layers "B.Cu" "B.Mask" "B.Paste")
			(net "PVDDCR_CPU1_P0")
		)
		(pad "2" smd circle
			(at -0.40005 0)
			(size 0 0)
			(layers "B.Cu" "B.Mask" "B.Paste")
			(net "GND")
		)
	)
	(footprint ""
		(layer "B.Cu")
		(at 393.153138 -391.2616 180)
		(property "Reference" "R1125"
			(at 0 0 0)
			(layer "B.SilkS")
			(hide yes)
			(effects
				(font
					(size 1.27 1.27)
				)
				(justify mirror)
			)
		)
		(property "Value" ""
			(at 0 0 0)
			(layer "B.Fab")
			(effects
				(font
					(size 1.27 1.27)
				)
				(justify mirror)
			)
		)
		(duplicate_pad_numbers_are_jumpers no)
		(fp_line
			(start 0.32512 0.175006)
			(end 0.32512 -0.175006)
			(stroke
				(width 0.1)
				(type default)
			)
			(layer "B.Fab")
		)
		(fp_line
			(start 0.32512 -0.175006)
			(end -0.32512 -0.175006)
			(stroke
				(width 0.1)
				(type default)
			)
			(layer "B.Fab")
		)
		(fp_line
			(start -0.32512 0.175006)
			(end 0.32512 0.175006)
			(stroke
				(width 0.1)
				(type default)
			)
			(layer "B.Fab")
		)
		(fp_line
			(start -0.32512 -0.175006)
			(end -0.32512 0.175006)
			(stroke
				(width 0.1)
				(type default)
			)
			(layer "B.Fab")
		)
		(pad "1" smd rect
			(at 0.2667 0)
			(size 0.3048 0.381)
			(layers "B.Cu" "B.Mask" "B.Paste")
			(net "NCF_CPU0_P3_GND")
		)
		(pad "2" smd rect
			(at -0.2667 0 180)
			(size 0.3048 0.381)
			(layers "B.Cu" "B.Mask" "B.Paste")
			(net "GND")
		)
	)
	(footprint ""
		(layer "B.Cu")
		(at 345.50604 -395.148562 90)
		(property "Reference" "C602"
			(at 0 0 90)
			(layer "B.SilkS")
			(hide yes)
			(effects
				(font
					(size 1.27 1.27)
				)
				(justify mirror)
			)
		)
		(property "Value" ""
			(at 0 0 90)
			(layer "B.Fab")
			(effects
				(font
					(size 1.27 1.27)
				)
				(justify mirror)
			)
		)
		(duplicate_pad_numbers_are_jumpers no)
		(fp_line
			(start 0.299974 -0.150114)
			(end -0.299974 -0.150114)
			(stroke
				(width 0.1)
				(type default)
			)
			(layer "B.Fab")
		)
		(fp_line
			(start -0.299974 -0.150114)
			(end -0.299974 0.150114)
			(stroke
				(width 0.1)
				(type default)
			)
			(layer "B.Fab")
		)
		(fp_line
			(start 0.299974 0.150114)
			(end 0.299974 -0.150114)
			(stroke
				(width 0.1)
				(type default)
			)
			(layer "B.Fab")
		)
		(fp_line
			(start -0.299974 0.150114)
			(end 0.299974 0.150114)
			(stroke
				(width 0.1)
				(type default)
			)
			(layer "B.Fab")
		)
		(pad "1" smd rect
			(at 0.2667 0 270)
			(size 0.3048 0.381)
			(layers "B.Cu" "B.Mask" "B.Paste")
			(net "P1V8_CPU0_RT1_1A")
		)
		(pad "2" smd rect
			(at -0.2667 0 270)
			(size 0.3048 0.381)
			(layers "B.Cu" "B.Mask" "B.Paste")
			(net "GND")
		)
	)
)
